(kicad_pcb
	(version 20260206)
	(generator "pcbnew")
	(generator_version "10.0")
	(general
		(thickness 1.6)
		(legacy_teardrops no)
	)
	(paper "A4")
	(title_block
		(title "12092022_DA0F0TMDCD0_F0T_Management_Board_D_brd_V3_OCP.brd")
		(comment 1 "Grand Teton / footprints 546-552 of 1440")
	)
	(layers
		(0 "F.Cu" signal "TOP")
		(4 "In1.Cu" signal "GND")
		(6 "In2.Cu" signal "IN1")
		(8 "In3.Cu" signal "GND1")
		(10 "In4.Cu" signal "IN2")
		(12 "In5.Cu" signal "VCC")
		(14 "In6.Cu" signal "VCC1")
		(16 "In7.Cu" signal "IN3")
		(18 "In8.Cu" signal "GND2")
		(20 "In9.Cu" signal "IN4")
		(22 "In10.Cu" signal "GND3")
		(2 "B.Cu" signal "BOTTOM")
		(9 "F.Adhes" user "F.Adhesive")
		(11 "B.Adhes" user "B.Adhesive")
		(13 "F.Paste" user "Package Geometry/Pastemask Top")
		(15 "B.Paste" user "Package Geometry/Pastemask Bottom")
		(5 "F.SilkS" user "Ref Des/Silkscreen Top")
		(7 "B.SilkS" user "Ref Des/Silkscreen Bottom")
		(1 "F.Mask" user "Board Geometry/Soldermask Top")
		(3 "B.Mask" user "Board Geometry/Soldermask Bottom")
		(17 "Dwgs.User" user "User.Drawings")
		(19 "Cmts.User" user "User.Comments")
		(21 "Eco1.User" user "User.Eco1")
		(23 "Eco2.User" user "User.Eco2")
		(25 "Edge.Cuts" user "Board Geometry/Outline")
		(27 "Margin" user)
		(31 "F.CrtYd" user "Package Geometry/Place Bound Top")
		(29 "B.CrtYd" user "Package Geometry/Place Bound Bottom")
		(35 "F.Fab" user "Ref Des/Assembly Top")
		(33 "B.Fab" user "Ref Des/Assembly Bottom")
	)
	(footprint ""
		(layer "F.Cu")
		(at 19.177 -39.751 -90)
		(property "Reference" "C280"
			(at 0 0 270)
			(layer "F.SilkS")
			(hide yes)
			(effects
				(font
					(size 1.27 1.27)
				)
			)
		)
		(property "Value" ""
			(at 0 0 270)
			(layer "F.Fab")
			(effects
				(font
					(size 1.27 1.27)
				)
			)
		)
		(duplicate_pad_numbers_are_jumpers no)
		(fp_line
			(start -0.7874 0.4064)
			(end -0.7874 -0.4064)
			(stroke
				(width 0.1524)
				(type default)
			)
			(layer "F.SilkS")
		)
		(fp_line
			(start 0.7874 0.4064)
			(end -0.7874 0.4064)
			(stroke
				(width 0.1524)
				(type default)
			)
			(layer "F.SilkS")
		)
		(fp_line
			(start -0.7874 -0.4064)
			(end 0.7874 -0.4064)
			(stroke
				(width 0.1524)
				(type default)
			)
			(layer "F.SilkS")
		)
		(fp_line
			(start 0.7874 -0.4064)
			(end 0.7874 0.4064)
			(stroke
				(width 0.1524)
				(type default)
			)
			(layer "F.SilkS")
		)
		(fp_line
			(start -0.67945 0.3048)
			(end -0.67945 -0.305054)
			(stroke
				(width 0.1)
				(type default)
			)
			(layer "F.Fab")
		)
		(fp_line
			(start -0.12065 0.3048)
			(end -0.67945 0.3048)
			(stroke
				(width 0.1)
				(type default)
			)
			(layer "F.Fab")
		)
		(fp_line
			(start 0.120396 0.3048)
			(end 0.120396 0.2794)
			(stroke
				(width 0.1)
				(type default)
			)
			(layer "F.Fab")
		)
		(fp_line
			(start 0.67945 0.3048)
			(end 0.120396 0.3048)
			(stroke
				(width 0.1)
				(type default)
			)
			(layer "F.Fab")
		)
		(fp_line
			(start -0.12065 0.2794)
			(end -0.12065 0.3048)
			(stroke
				(width 0.1)
				(type default)
			)
			(layer "F.Fab")
		)
		(fp_line
			(start 0.120396 0.2794)
			(end -0.12065 0.2794)
			(stroke
				(width 0.1)
				(type default)
			)
			(layer "F.Fab")
		)
		(fp_line
			(start -0.12065 -0.2794)
			(end 0.12065 -0.2794)
			(stroke
				(width 0.1)
				(type default)
			)
			(layer "F.Fab")
		)
		(fp_line
			(start 0.12065 -0.2794)
			(end 0.12065 -0.3048)
			(stroke
				(width 0.1)
				(type default)
			)
			(layer "F.Fab")
		)
		(fp_line
			(start 0.12065 -0.3048)
			(end 0.67945 -0.3048)
			(stroke
				(width 0.1)
				(type default)
			)
			(layer "F.Fab")
		)
		(fp_line
			(start 0.67945 -0.3048)
			(end 0.67945 0.3048)
			(stroke
				(width 0.1)
				(type default)
			)
			(layer "F.Fab")
		)
		(fp_line
			(start -0.67945 -0.305054)
			(end -0.12065 -0.305054)
			(stroke
				(width 0.1)
				(type default)
			)
			(layer "F.Fab")
		)
		(fp_line
			(start -0.12065 -0.305054)
			(end -0.12065 -0.2794)
			(stroke
				(width 0.1)
				(type default)
			)
			(layer "F.Fab")
		)
		(pad "1" smd circle
			(at -0.40005 0 270)
			(size 0 0)
			(layers "F.Cu" "F.Mask" "F.Paste")
			(net "P12V_AUX")
		)
		(pad "2" smd circle
			(at 0.40005 0 270)
			(size 0 0)
			(layers "F.Cu" "F.Mask" "F.Paste")
			(net "GND")
		)
	)
	(footprint ""
		(layer "F.Cu")
		(at 23.064216 -84.28228 90)
		(property "Reference" "R634"
			(at 0 0 90)
			(layer "F.SilkS")
			(hide yes)
			(effects
				(font
					(size 1.27 1.27)
				)
			)
		)
		(property "Value" ""
			(at 0 0 90)
			(layer "F.Fab")
			(effects
				(font
					(size 1.27 1.27)
				)
			)
		)
		(duplicate_pad_numbers_are_jumpers no)
		(fp_line
			(start 0.7874 -0.4064)
			(end 0.7874 0.4064)
			(stroke
				(width 0.1524)
				(type default)
			)
			(layer "F.SilkS")
		)
		(fp_line
			(start -0.7874 -0.4064)
			(end 0.7874 -0.4064)
			(stroke
				(width 0.1524)
				(type default)
			)
			(layer "F.SilkS")
		)
		(fp_line
			(start 0.7874 0.4064)
			(end -0.7874 0.4064)
			(stroke
				(width 0.1524)
				(type default)
			)
			(layer "F.SilkS")
		)
		(fp_line
			(start -0.7874 0.4064)
			(end -0.7874 -0.4064)
			(stroke
				(width 0.1524)
				(type default)
			)
			(layer "F.SilkS")
		)
		(fp_line
			(start -0.12065 -0.305054)
			(end -0.12065 -0.2794)
			(stroke
				(width 0.1)
				(type default)
			)
			(layer "F.Fab")
		)
		(fp_line
			(start -0.67945 -0.305054)
			(end -0.12065 -0.305054)
			(stroke
				(width 0.1)
				(type default)
			)
			(layer "F.Fab")
		)
		(fp_line
			(start 0.67945 -0.3048)
			(end 0.67945 0.3048)
			(stroke
				(width 0.1)
				(type default)
			)
			(layer "F.Fab")
		)
		(fp_line
			(start 0.12065 -0.3048)
			(end 0.67945 -0.3048)
			(stroke
				(width 0.1)
				(type default)
			)
			(layer "F.Fab")
		)
		(fp_line
			(start 0.12065 -0.2794)
			(end 0.12065 -0.3048)
			(stroke
				(width 0.1)
				(type default)
			)
			(layer "F.Fab")
		)
		(fp_line
			(start -0.12065 -0.2794)
			(end 0.12065 -0.2794)
			(stroke
				(width 0.1)
				(type default)
			)
			(layer "F.Fab")
		)
		(fp_line
			(start 0.120396 0.2794)
			(end -0.12065 0.2794)
			(stroke
				(width 0.1)
				(type default)
			)
			(layer "F.Fab")
		)
		(fp_line
			(start -0.12065 0.2794)
			(end -0.12065 0.3048)
			(stroke
				(width 0.1)
				(type default)
			)
			(layer "F.Fab")
		)
		(fp_line
			(start 0.67945 0.3048)
			(end 0.120396 0.3048)
			(stroke
				(width 0.1)
				(type default)
			)
			(layer "F.Fab")
		)
		(fp_line
			(start 0.120396 0.3048)
			(end 0.120396 0.2794)
			(stroke
				(width 0.1)
				(type default)
			)
			(layer "F.Fab")
		)
		(fp_line
			(start -0.12065 0.3048)
			(end -0.67945 0.3048)
			(stroke
				(width 0.1)
				(type default)
			)
			(layer "F.Fab")
		)
		(fp_line
			(start -0.67945 0.3048)
			(end -0.67945 -0.305054)
			(stroke
				(width 0.1)
				(type default)
			)
			(layer "F.Fab")
		)
		(pad "1" smd circle
			(at -0.40005 0 90)
			(size 0 0)
			(layers "F.Cu" "F.Mask" "F.Paste")
			(net "FM_JTAG_BMC_MUX_SEL")
		)
		(pad "2" smd circle
			(at 0.40005 0 90)
			(size 0 0)
			(layers "F.Cu" "F.Mask" "F.Paste")
			(net "FM_JTAG_BMC_MUX_SEL_R2")
		)
	)
	(footprint ""
		(layer "F.Cu")
		(at 39.826946 -79.64424 180)
		(property "Reference" "R557"
			(at 0 0 180)
			(layer "F.SilkS")
			(hide yes)
			(effects
				(font
					(size 1.27 1.27)
				)
			)
		)
		(property "Value" ""
			(at 0 0 180)
			(layer "F.Fab")
			(effects
				(font
					(size 1.27 1.27)
				)
			)
		)
		(duplicate_pad_numbers_are_jumpers no)
		(fp_line
			(start 0.7874 0.4064)
			(end -0.7874 0.4064)
			(stroke
				(width 0.1524)
				(type default)
			)
			(layer "F.SilkS")
		)
		(fp_line
			(start 0.7874 -0.4064)
			(end 0.7874 0.4064)
			(stroke
				(width 0.1524)
				(type default)
			)
			(layer "F.SilkS")
		)
		(fp_line
			(start -0.7874 0.4064)
			(end -0.7874 -0.4064)
			(stroke
				(width 0.1524)
				(type default)
			)
			(layer "F.SilkS")
		)
		(fp_line
			(start -0.7874 -0.4064)
			(end 0.7874 -0.4064)
			(stroke
				(width 0.1524)
				(type default)
			)
			(layer "F.SilkS")
		)
		(fp_line
			(start 0.67945 0.3048)
			(end 0.120396 0.3048)
			(stroke
				(width 0.1)
				(type default)
			)
			(layer "F.Fab")
		)
		(fp_line
			(start 0.67945 -0.3048)
			(end 0.67945 0.3048)
			(stroke
				(width 0.1)
				(type default)
			)
			(layer "F.Fab")
		)
		(fp_line
			(start 0.12065 -0.2794)
			(end 0.12065 -0.3048)
			(stroke
				(width 0.1)
				(type default)
			)
			(layer "F.Fab")
		)
		(fp_line
			(start 0.12065 -0.3048)
			(end 0.67945 -0.3048)
			(stroke
				(width 0.1)
				(type default)
			)
			(layer "F.Fab")
		)
		(fp_line
			(start 0.120396 0.3048)
			(end 0.120396 0.2794)
			(stroke
				(width 0.1)
				(type default)
			)
			(layer "F.Fab")
		)
		(fp_line
			(start 0.120396 0.2794)
			(end -0.12065 0.2794)
			(stroke
				(width 0.1)
				(type default)
			)
			(layer "F.Fab")
		)
		(fp_line
			(start -0.12065 0.3048)
			(end -0.67945 0.3048)
			(stroke
				(width 0.1)
				(type default)
			)
			(layer "F.Fab")
		)
		(fp_line
			(start -0.12065 0.2794)
			(end -0.12065 0.3048)
			(stroke
				(width 0.1)
				(type default)
			)
			(layer "F.Fab")
		)
		(fp_line
			(start -0.12065 -0.2794)
			(end 0.12065 -0.2794)
			(stroke
				(width 0.1)
				(type default)
			)
			(layer "F.Fab")
		)
		(fp_line
			(start -0.12065 -0.305054)
			(end -0.12065 -0.2794)
			(stroke
				(width 0.1)
				(type default)
			)
			(layer "F.Fab")
		)
		(fp_line
			(start -0.67945 0.3048)
			(end -0.67945 -0.305054)
			(stroke
				(width 0.1)
				(type default)
			)
			(layer "F.Fab")
		)
		(fp_line
			(start -0.67945 -0.305054)
			(end -0.12065 -0.305054)
			(stroke
				(width 0.1)
				(type default)
			)
			(layer "F.Fab")
		)
		(pad "1" smd circle
			(at -0.40005 0 180)
			(size 0 0)
			(layers "F.Cu" "F.Mask" "F.Paste")
			(net "P3V3_AUX")
		)
		(pad "2" smd circle
			(at 0.40005 0 180)
			(size 0 0)
			(layers "F.Cu" "F.Mask" "F.Paste")
			(net "SPI_BMC_CS0_FLASH_R_N")
		)
	)
	(footprint ""
		(layer "F.Cu")
		(at 17.7165 -69.596 -90)
		(property "Reference" "C234"
			(at 0 0 270)
			(layer "F.SilkS")
			(hide yes)
			(effects
				(font
					(size 1.27 1.27)
				)
			)
		)
		(property "Value" ""
			(at 0 0 270)
			(layer "F.Fab")
			(effects
				(font
					(size 1.27 1.27)
				)
			)
		)
		(duplicate_pad_numbers_are_jumpers no)
		(fp_line
			(start -1.2954 0.5842)
			(end -1.2954 -0.5842)
			(stroke
				(width 0.1524)
				(type default)
			)
			(layer "F.SilkS")
		)
		(fp_line
			(start 1.2954 0.5842)
			(end -1.2954 0.5842)
			(stroke
				(width 0.1524)
				(type default)
			)
			(layer "F.SilkS")
		)
		(fp_line
			(start -1.2954 -0.5842)
			(end 1.2954 -0.5842)
			(stroke
				(width 0.1524)
				(type default)
			)
			(layer "F.SilkS")
		)
		(fp_line
			(start 0 -0.5842)
			(end 0 0.5842)
			(stroke
				(width 0.1524)
				(type default)
			)
			(layer "F.SilkS")
		)
		(fp_line
			(start 1.2954 -0.5842)
			(end 1.2954 0.5842)
			(stroke
				(width 0.1524)
				(type default)
			)
			(layer "F.SilkS")
		)
		(fp_line
			(start -0.8636 0.4572)
			(end -0.8636 0.4064)
			(stroke
				(width 0.1)
				(type default)
			)
			(layer "F.Fab")
		)
		(fp_line
			(start 0.8636 0.4572)
			(end -0.8636 0.4572)
			(stroke
				(width 0.1)
				(type default)
			)
			(layer "F.Fab")
		)
		(fp_line
			(start -1.1938 0.4064)
			(end -1.1938 -0.4064)
			(stroke
				(width 0.1)
				(type default)
			)
			(layer "F.Fab")
		)
		(fp_line
			(start -0.8636 0.4064)
			(end -1.1938 0.4064)
			(stroke
				(width 0.1)
				(type default)
			)
			(layer "F.Fab")
		)
		(fp_line
			(start 0.8636 0.4064)
			(end 0.8636 0.4572)
			(stroke
				(width 0.1)
				(type default)
			)
			(layer "F.Fab")
		)
		(fp_line
			(start 1.1938 0.4064)
			(end 0.8636 0.4064)
			(stroke
				(width 0.1)
				(type default)
			)
			(layer "F.Fab")
		)
		(fp_line
			(start -1.1938 -0.4064)
			(end -0.8636 -0.4064)
			(stroke
				(width 0.1)
				(type default)
			)
			(layer "F.Fab")
		)
		(fp_line
			(start -0.8636 -0.4064)
			(end -0.8636 -0.4572)
			(stroke
				(width 0.1)
				(type default)
			)
			(layer "F.Fab")
		)
		(fp_line
			(start 0.8636 -0.4064)
			(end 1.1938 -0.4064)
			(stroke
				(width 0.1)
				(type default)
			)
			(layer "F.Fab")
		)
		(fp_line
			(start 1.1938 -0.4064)
			(end 1.1938 0.4064)
			(stroke
				(width 0.1)
				(type default)
			)
			(layer "F.Fab")
		)
		(fp_line
			(start -0.8636 -0.4572)
			(end 0.8636 -0.4572)
			(stroke
				(width 0.1)
				(type default)
			)
			(layer "F.Fab")
		)
		(fp_line
			(start 0.8636 -0.4572)
			(end 0.8636 -0.4064)
			(stroke
				(width 0.1)
				(type default)
			)
			(layer "F.Fab")
		)
		(pad "1" smd rect
			(at -0.7366 0 180)
			(size 0.7112 0.8128)
			(layers "F.Cu" "F.Mask" "F.Paste")
			(net "P3V3_AUX")
		)
		(pad "2" smd rect
			(at 0.7366 0 180)
			(size 0.7112 0.8128)
			(layers "F.Cu" "F.Mask" "F.Paste")
			(net "GND")
		)
	)
	(footprint ""
		(layer "F.Cu")
		(at 5.599938 -11.789918)
		(property "Reference" "H6"
			(at -4.964938 0.005588 0)
			(unlocked yes)
			(layer "F.SilkS")
			(effects
				(font
					(size 0.7874 0.5842)
					(thickness 0.1524)
				)
				(justify left)
			)
		)
		(property "Value" ""
			(at 0 0 0)
			(layer "F.Fab")
			(effects
				(font
					(size 1.27 1.27)
				)
			)
		)
		(duplicate_pad_numbers_are_jumpers no)
		(pad "1" thru_hole circle
			(at 0 0)
			(size 6.5024 6.5024)
			(drill 3.2004)
			(layers "*.Cu" "*.Mask")
			(remove_unused_layers no)
			(net "GND")
			(clearance -1.397)
		)
	)
	(footprint ""
		(layer "F.Cu")
		(at 44.704 -34.6202 90)
		(property "Reference" "R762"
			(at 0 0 90)
			(layer "F.SilkS")
			(hide yes)
			(effects
				(font
					(size 1.27 1.27)
				)
			)
		)
		(property "Value" ""
			(at 0 0 90)
			(layer "F.Fab")
			(effects
				(font
					(size 1.27 1.27)
				)
			)
		)
		(duplicate_pad_numbers_are_jumpers no)
		(fp_line
			(start 0.7874 -0.4064)
			(end 0.7874 0.4064)
			(stroke
				(width 0.1524)
				(type default)
			)
			(layer "F.SilkS")
		)
		(fp_line
			(start -0.7874 -0.4064)
			(end 0.7874 -0.4064)
			(stroke
				(width 0.1524)
				(type default)
			)
			(layer "F.SilkS")
		)
		(fp_line
			(start 0.7874 0.4064)
			(end -0.7874 0.4064)
			(stroke
				(width 0.1524)
				(type default)
			)
			(layer "F.SilkS")
		)
		(fp_line
			(start -0.7874 0.4064)
			(end -0.7874 -0.4064)
			(stroke
				(width 0.1524)
				(type default)
			)
			(layer "F.SilkS")
		)
		(fp_line
			(start -0.12065 -0.305054)
			(end -0.12065 -0.2794)
			(stroke
				(width 0.1)
				(type default)
			)
			(layer "F.Fab")
		)
		(fp_line
			(start -0.67945 -0.305054)
			(end -0.12065 -0.305054)
			(stroke
				(width 0.1)
				(type default)
			)
			(layer "F.Fab")
		)
		(fp_line
			(start 0.67945 -0.3048)
			(end 0.67945 0.3048)
			(stroke
				(width 0.1)
				(type default)
			)
			(layer "F.Fab")
		)
		(fp_line
			(start 0.12065 -0.3048)
			(end 0.67945 -0.3048)
			(stroke
				(width 0.1)
				(type default)
			)
			(layer "F.Fab")
		)
		(fp_line
			(start 0.12065 -0.2794)
			(end 0.12065 -0.3048)
			(stroke
				(width 0.1)
				(type default)
			)
			(layer "F.Fab")
		)
		(fp_line
			(start -0.12065 -0.2794)
			(end 0.12065 -0.2794)
			(stroke
				(width 0.1)
				(type default)
			)
			(layer "F.Fab")
		)
		(fp_line
			(start 0.120396 0.2794)
			(end -0.12065 0.2794)
			(stroke
				(width 0.1)
				(type default)
			)
			(layer "F.Fab")
		)
		(fp_line
			(start -0.12065 0.2794)
			(end -0.12065 0.3048)
			(stroke
				(width 0.1)
				(type default)
			)
			(layer "F.Fab")
		)
		(fp_line
			(start 0.67945 0.3048)
			(end 0.120396 0.3048)
			(stroke
				(width 0.1)
				(type default)
			)
			(layer "F.Fab")
		)
		(fp_line
			(start 0.120396 0.3048)
			(end 0.120396 0.2794)
			(stroke
				(width 0.1)
				(type default)
			)
			(layer "F.Fab")
		)
		(fp_line
			(start -0.12065 0.3048)
			(end -0.67945 0.3048)
			(stroke
				(width 0.1)
				(type default)
			)
			(layer "F.Fab")
		)
		(fp_line
			(start -0.67945 0.3048)
			(end -0.67945 -0.305054)
			(stroke
				(width 0.1)
				(type default)
			)
			(layer "F.Fab")
		)
		(pad "1" smd circle
			(at -0.40005 0 90)
			(size 0 0)
			(layers "F.Cu" "F.Mask" "F.Paste")
			(net "UART_6_BMC_RXD")
		)
		(pad "2" smd circle
			(at 0.40005 0 90)
			(size 0 0)
			(layers "F.Cu" "F.Mask" "F.Paste")
			(net "UART_6_BMC_R_RXD")
		)
	)
	(footprint ""
		(layer "F.Cu")
		(at 76.581 -82.677 -90)
		(property "Reference" "U56"
			(at 1.5494 2.149348 90)
			(unlocked yes)
			(layer "F.SilkS")
			(effects
				(font
					(size 0.7874 0.5842)
					(thickness 0.1524)
				)
				(justify left)
			)
		)
		(property "Value" ""
			(at 0 0 270)
			(layer "F.Fab")
			(effects
				(font
					(size 1.27 1.27)
				)
			)
		)
		(duplicate_pad_numbers_are_jumpers no)
		(fp_line
			(start -1.934972 1.549908)
			(end 1.934972 1.549908)
			(stroke
				(width 0.1524)
				(type default)
			)
			(layer "F.SilkS")
		)
		(fp_line
			(start 1.934972 1.549908)
			(end 1.934972 -1.549908)
			(stroke
				(width 0.1524)
				(type default)
			)
			(layer "F.SilkS")
		)
		(fp_line
			(start 0 -0.82042)
			(end -0.475742 -1.549908)
			(stroke
				(width 0.1524)
				(type default)
			)
			(layer "F.SilkS")
		)
		(fp_line
			(start -1.934972 -1.549908)
			(end -1.934972 1.549908)
			(stroke
				(width 0.1524)
				(type default)
			)
			(layer "F.SilkS")
		)
		(fp_line
			(start -0.475742 -1.549908)
			(end -1.934972 -1.549908)
			(stroke
				(width 0.1524)
				(type default)
			)
			(layer "F.SilkS")
		)
		(fp_line
			(start 0.475742 -1.549908)
			(end 0 -0.82042)
			(stroke
				(width 0.1524)
				(type default)
			)
			(layer "F.SilkS")
		)
		(fp_line
			(start 1.934972 -1.549908)
			(end 0.475742 -1.549908)
			(stroke
				(width 0.1524)
				(type default)
			)
			(layer "F.SilkS")
		)
		(fp_poly
			(pts
				(xy -3.160522 -1.45796) (xy -3.160522 -0.44196) (xy -2.144522 -0.94996)
			)
			(stroke
				(width 0)
				(type default)
			)
			(fill yes)
			(layer "F.SilkS")
		)
		(fp_line
			(start -0.849884 1.549908)
			(end 0.849884 1.549908)
			(stroke
				(width 0.1)
				(type default)
			)
			(layer "F.Fab")
		)
		(fp_line
			(start 0.849884 1.549908)
			(end 0.849884 -1.549908)
			(stroke
				(width 0.1)
				(type default)
			)
			(layer "F.Fab")
		)
		(fp_line
			(start -0.849884 -1.549908)
			(end -0.849884 1.549908)
			(stroke
				(width 0.1)
				(type default)
			)
			(layer "F.Fab")
		)
		(fp_line
			(start 0.849884 -1.549908)
			(end -0.849884 -1.549908)
			(stroke
				(width 0.1)
				(type default)
			)
			(layer "F.Fab")
		)
		(fp_poly
			(pts
				(xy -3.160522 -1.45796) (xy -3.160522 -0.44196) (xy -2.144522 -0.94996)
			)
			(stroke
				(width 0)
				(type default)
			)
			(fill yes)
			(layer "F.Fab")
		)
		(pad "1" smd rect
			(at -1.299972 -0.94996 180)
			(size 0.7112 1.016)
			(layers "F.Cu" "F.Mask" "F.Paste")
			(net "P12V_AUX")
		)
		(pad "2" smd rect
			(at -1.299972 0 180)
			(size 0.7112 1.016)
			(layers "F.Cu" "F.Mask" "F.Paste")
			(net "GND")
		)
		(pad "3" smd rect
			(at -1.299972 0.94996 180)
			(size 0.7112 1.016)
			(layers "F.Cu" "F.Mask" "F.Paste")
			(net "P12V_AUX")
		)
		(pad "4" smd rect
			(at 1.299972 0.94996 180)
			(size 0.7112 1.016)
			(layers "F.Cu" "F.Mask" "F.Paste")
			(net "U56_ADJ_1")
		)
		(pad "5" smd rect
			(at 1.299972 -0.94996 180)
			(size 0.7112 1.016)
			(layers "F.Cu" "F.Mask" "F.Paste")
			(net "P3V3_LDO")
		)
	)
)
